(kicad_pcb
	(version 20260206)
	(generator "pcbnew")
	(generator_version "10.0")
	(general
		(thickness 1.6)
		(legacy_teardrops no)
	)
	(paper "A4")
	(title_block
		(title "9052_F0T_PDB_Converter_Brick_F_V03_1208_1600_OCP.brd")
		(comment 1 "Grand Teton / footprints 421-426 of 578")
	)
	(layers
		(0 "F.Cu" signal "TOP")
		(4 "In1.Cu" signal "GND")
		(6 "In2.Cu" signal "IN1")
		(8 "In3.Cu" signal "GND1")
		(10 "In4.Cu" signal "VCC")
		(12 "In5.Cu" signal "VCC1")
		(14 "In6.Cu" signal "GND2")
		(16 "In7.Cu" signal "IN2")
		(18 "In8.Cu" signal "GND3")
		(2 "B.Cu" signal "BOTTOM")
		(9 "F.Adhes" user "F.Adhesive")
		(11 "B.Adhes" user "B.Adhesive")
		(13 "F.Paste" user "Package Geometry/Pastemask Top")
		(15 "B.Paste" user "Package Geometry/Pastemask Bottom")
		(5 "F.SilkS" user "Ref Des/Silkscreen Top")
		(7 "B.SilkS" user "Ref Des/Silkscreen Bottom")
		(1 "F.Mask" user "Board Geometry/Soldermask Top")
		(3 "B.Mask" user "Board Geometry/Soldermask Bottom")
		(17 "Dwgs.User" user "User.Drawings")
		(19 "Cmts.User" user "User.Comments")
		(21 "Eco1.User" user "User.Eco1")
		(23 "Eco2.User" user "User.Eco2")
		(25 "Edge.Cuts" user "Board Geometry/Outline")
		(27 "Margin" user)
		(31 "F.CrtYd" user "Package Geometry/Place Bound Top")
		(29 "B.CrtYd" user "Package Geometry/Place Bound Bottom")
		(35 "F.Fab" user "Ref Des/Assembly Top")
		(33 "B.Fab" user "Ref Des/Assembly Bottom")
	)
	(footprint ""
		(layer "B.Cu")
		(at 271.145 -40.132 90)
		(property "Reference" "R5933"
			(at 0 0 90)
			(layer "B.SilkS")
			(hide yes)
			(effects
				(font
					(size 1.27 1.27)
				)
				(justify mirror)
			)
		)
		(property "Value" ""
			(at 0 0 90)
			(layer "B.Fab")
			(effects
				(font
					(size 1.27 1.27)
				)
				(justify mirror)
			)
		)
		(duplicate_pad_numbers_are_jumpers no)
		(fp_line
			(start 0.7874 -0.4064)
			(end -0.7874 -0.4064)
			(stroke
				(width 0.1524)
				(type default)
			)
			(layer "B.SilkS")
		)
		(fp_line
			(start -0.7874 -0.4064)
			(end -0.7874 0.4064)
			(stroke
				(width 0.1524)
				(type default)
			)
			(layer "B.SilkS")
		)
		(fp_line
			(start 0.7874 0.4064)
			(end 0.7874 -0.4064)
			(stroke
				(width 0.1524)
				(type default)
			)
			(layer "B.SilkS")
		)
		(fp_line
			(start -0.7874 0.4064)
			(end 0.7874 0.4064)
			(stroke
				(width 0.1524)
				(type default)
			)
			(layer "B.SilkS")
		)
		(fp_line
			(start 0.67945 -0.305054)
			(end 0.12065 -0.305054)
			(stroke
				(width 0.1)
				(type default)
			)
			(layer "B.Fab")
		)
		(fp_line
			(start 0.12065 -0.305054)
			(end 0.12065 -0.2794)
			(stroke
				(width 0.1)
				(type default)
			)
			(layer "B.Fab")
		)
		(fp_line
			(start -0.12065 -0.3048)
			(end -0.67945 -0.3048)
			(stroke
				(width 0.1)
				(type default)
			)
			(layer "B.Fab")
		)
		(fp_line
			(start -0.67945 -0.3048)
			(end -0.67945 0.3048)
			(stroke
				(width 0.1)
				(type default)
			)
			(layer "B.Fab")
		)
		(fp_line
			(start 0.12065 -0.2794)
			(end -0.12065 -0.2794)
			(stroke
				(width 0.1)
				(type default)
			)
			(layer "B.Fab")
		)
		(fp_line
			(start -0.12065 -0.2794)
			(end -0.12065 -0.3048)
			(stroke
				(width 0.1)
				(type default)
			)
			(layer "B.Fab")
		)
		(fp_line
			(start 0.12065 0.2794)
			(end 0.12065 0.3048)
			(stroke
				(width 0.1)
				(type default)
			)
			(layer "B.Fab")
		)
		(fp_line
			(start -0.120396 0.2794)
			(end 0.12065 0.2794)
			(stroke
				(width 0.1)
				(type default)
			)
			(layer "B.Fab")
		)
		(fp_line
			(start 0.67945 0.3048)
			(end 0.67945 -0.305054)
			(stroke
				(width 0.1)
				(type default)
			)
			(layer "B.Fab")
		)
		(fp_line
			(start 0.12065 0.3048)
			(end 0.67945 0.3048)
			(stroke
				(width 0.1)
				(type default)
			)
			(layer "B.Fab")
		)
		(fp_line
			(start -0.120396 0.3048)
			(end -0.120396 0.2794)
			(stroke
				(width 0.1)
				(type default)
			)
			(layer "B.Fab")
		)
		(fp_line
			(start -0.67945 0.3048)
			(end -0.120396 0.3048)
			(stroke
				(width 0.1)
				(type default)
			)
			(layer "B.Fab")
		)
		(pad "1" smd circle
			(at 0.40005 0 270)
			(size 0 0)
			(layers "B.Cu" "B.Mask" "B.Paste")
			(net "P52V_HS1_EN_BUF_DELAY")
		)
		(pad "2" smd circle
			(at -0.40005 0 270)
			(size 0 0)
			(layers "B.Cu" "B.Mask" "B.Paste")
			(net "GND")
		)
	)
	(footprint ""
		(layer "B.Cu")
		(at 204.851 -71.374 -90)
		(property "Reference" "R5909"
			(at 0 0 90)
			(layer "B.SilkS")
			(hide yes)
			(effects
				(font
					(size 1.27 1.27)
				)
				(justify mirror)
			)
		)
		(property "Value" ""
			(at 0 0 90)
			(layer "B.Fab")
			(effects
				(font
					(size 1.27 1.27)
				)
				(justify mirror)
			)
		)
		(duplicate_pad_numbers_are_jumpers no)
		(fp_line
			(start -0.7874 0.4064)
			(end 0.7874 0.4064)
			(stroke
				(width 0.1524)
				(type default)
			)
			(layer "B.SilkS")
		)
		(fp_line
			(start 0.7874 0.4064)
			(end 0.7874 -0.4064)
			(stroke
				(width 0.1524)
				(type default)
			)
			(layer "B.SilkS")
		)
		(fp_line
			(start -0.7874 -0.4064)
			(end -0.7874 0.4064)
			(stroke
				(width 0.1524)
				(type default)
			)
			(layer "B.SilkS")
		)
		(fp_line
			(start 0.7874 -0.4064)
			(end -0.7874 -0.4064)
			(stroke
				(width 0.1524)
				(type default)
			)
			(layer "B.SilkS")
		)
		(fp_line
			(start -0.67945 0.3048)
			(end -0.120396 0.3048)
			(stroke
				(width 0.1)
				(type default)
			)
			(layer "B.Fab")
		)
		(fp_line
			(start -0.120396 0.3048)
			(end -0.120396 0.2794)
			(stroke
				(width 0.1)
				(type default)
			)
			(layer "B.Fab")
		)
		(fp_line
			(start 0.12065 0.3048)
			(end 0.67945 0.3048)
			(stroke
				(width 0.1)
				(type default)
			)
			(layer "B.Fab")
		)
		(fp_line
			(start 0.67945 0.3048)
			(end 0.67945 -0.305054)
			(stroke
				(width 0.1)
				(type default)
			)
			(layer "B.Fab")
		)
		(fp_line
			(start -0.120396 0.2794)
			(end 0.12065 0.2794)
			(stroke
				(width 0.1)
				(type default)
			)
			(layer "B.Fab")
		)
		(fp_line
			(start 0.12065 0.2794)
			(end 0.12065 0.3048)
			(stroke
				(width 0.1)
				(type default)
			)
			(layer "B.Fab")
		)
		(fp_line
			(start -0.12065 -0.2794)
			(end -0.12065 -0.3048)
			(stroke
				(width 0.1)
				(type default)
			)
			(layer "B.Fab")
		)
		(fp_line
			(start 0.12065 -0.2794)
			(end -0.12065 -0.2794)
			(stroke
				(width 0.1)
				(type default)
			)
			(layer "B.Fab")
		)
		(fp_line
			(start -0.67945 -0.3048)
			(end -0.67945 0.3048)
			(stroke
				(width 0.1)
				(type default)
			)
			(layer "B.Fab")
		)
		(fp_line
			(start -0.12065 -0.3048)
			(end -0.67945 -0.3048)
			(stroke
				(width 0.1)
				(type default)
			)
			(layer "B.Fab")
		)
		(fp_line
			(start 0.12065 -0.305054)
			(end 0.12065 -0.2794)
			(stroke
				(width 0.1)
				(type default)
			)
			(layer "B.Fab")
		)
		(fp_line
			(start 0.67945 -0.305054)
			(end 0.12065 -0.305054)
			(stroke
				(width 0.1)
				(type default)
			)
			(layer "B.Fab")
		)
		(pad "1" smd circle
			(at 0.40005 0 90)
			(size 0 0)
			(layers "B.Cu" "B.Mask" "B.Paste")
			(net "P3V3_AUX")
		)
		(pad "2" smd circle
			(at -0.40005 0 90)
			(size 0 0)
			(layers "B.Cu" "B.Mask" "B.Paste")
			(net "PRSNT_HPDB_N")
		)
	)
	(footprint ""
		(layer "B.Cu")
		(at 136.779 -76.327 180)
		(property "Reference" "R165"
			(at 0 0 0)
			(layer "B.SilkS")
			(hide yes)
			(effects
				(font
					(size 1.27 1.27)
				)
				(justify mirror)
			)
		)
		(property "Value" ""
			(at 0 0 0)
			(layer "B.Fab")
			(effects
				(font
					(size 1.27 1.27)
				)
				(justify mirror)
			)
		)
		(duplicate_pad_numbers_are_jumpers no)
		(fp_line
			(start 0.7874 0.4064)
			(end 0.7874 -0.4064)
			(stroke
				(width 0.1524)
				(type default)
			)
			(layer "B.SilkS")
		)
		(fp_line
			(start 0.7874 -0.4064)
			(end -0.7874 -0.4064)
			(stroke
				(width 0.1524)
				(type default)
			)
			(layer "B.SilkS")
		)
		(fp_line
			(start -0.7874 0.4064)
			(end 0.7874 0.4064)
			(stroke
				(width 0.1524)
				(type default)
			)
			(layer "B.SilkS")
		)
		(fp_line
			(start -0.7874 -0.4064)
			(end -0.7874 0.4064)
			(stroke
				(width 0.1524)
				(type default)
			)
			(layer "B.SilkS")
		)
		(fp_line
			(start 0.67945 0.3048)
			(end 0.67945 -0.305054)
			(stroke
				(width 0.1)
				(type default)
			)
			(layer "B.Fab")
		)
		(fp_line
			(start 0.67945 -0.305054)
			(end 0.12065 -0.305054)
			(stroke
				(width 0.1)
				(type default)
			)
			(layer "B.Fab")
		)
		(fp_line
			(start 0.12065 0.3048)
			(end 0.67945 0.3048)
			(stroke
				(width 0.1)
				(type default)
			)
			(layer "B.Fab")
		)
		(fp_line
			(start 0.12065 0.2794)
			(end 0.12065 0.3048)
			(stroke
				(width 0.1)
				(type default)
			)
			(layer "B.Fab")
		)
		(fp_line
			(start 0.12065 -0.2794)
			(end -0.12065 -0.2794)
			(stroke
				(width 0.1)
				(type default)
			)
			(layer "B.Fab")
		)
		(fp_line
			(start 0.12065 -0.305054)
			(end 0.12065 -0.2794)
			(stroke
				(width 0.1)
				(type default)
			)
			(layer "B.Fab")
		)
		(fp_line
			(start -0.120396 0.3048)
			(end -0.120396 0.2794)
			(stroke
				(width 0.1)
				(type default)
			)
			(layer "B.Fab")
		)
		(fp_line
			(start -0.120396 0.2794)
			(end 0.12065 0.2794)
			(stroke
				(width 0.1)
				(type default)
			)
			(layer "B.Fab")
		)
		(fp_line
			(start -0.12065 -0.2794)
			(end -0.12065 -0.3048)
			(stroke
				(width 0.1)
				(type default)
			)
			(layer "B.Fab")
		)
		(fp_line
			(start -0.12065 -0.3048)
			(end -0.67945 -0.3048)
			(stroke
				(width 0.1)
				(type default)
			)
			(layer "B.Fab")
		)
		(fp_line
			(start -0.67945 0.3048)
			(end -0.120396 0.3048)
			(stroke
				(width 0.1)
				(type default)
			)
			(layer "B.Fab")
		)
		(fp_line
			(start -0.67945 -0.3048)
			(end -0.67945 0.3048)
			(stroke
				(width 0.1)
				(type default)
			)
			(layer "B.Fab")
		)
		(pad "1" smd circle
			(at 0.40005 0)
			(size 0 0)
			(layers "B.Cu" "B.Mask" "B.Paste")
			(net "P12V_BRICK0_ALERT_N")
		)
		(pad "2" smd circle
			(at -0.40005 0)
			(size 0 0)
			(layers "B.Cu" "B.Mask" "B.Paste")
			(net "SMB_BRICK0_ALERT")
		)
	)
	(footprint ""
		(layer "B.Cu")
		(at 274.026122 -92.314522)
		(property "Reference" "R5861"
			(at 0 0 0)
			(layer "B.SilkS")
			(hide yes)
			(effects
				(font
					(size 1.27 1.27)
				)
				(justify mirror)
			)
		)
		(property "Value" ""
			(at 0 0 0)
			(layer "B.Fab")
			(effects
				(font
					(size 1.27 1.27)
				)
				(justify mirror)
			)
		)
		(duplicate_pad_numbers_are_jumpers no)
		(fp_line
			(start -0.7874 -0.4064)
			(end -0.7874 0.4064)
			(stroke
				(width 0.1524)
				(type default)
			)
			(layer "B.SilkS")
		)
		(fp_line
			(start -0.7874 0.4064)
			(end 0.7874 0.4064)
			(stroke
				(width 0.1524)
				(type default)
			)
			(layer "B.SilkS")
		)
		(fp_line
			(start 0.7874 -0.4064)
			(end -0.7874 -0.4064)
			(stroke
				(width 0.1524)
				(type default)
			)
			(layer "B.SilkS")
		)
		(fp_line
			(start 0.7874 0.4064)
			(end 0.7874 -0.4064)
			(stroke
				(width 0.1524)
				(type default)
			)
			(layer "B.SilkS")
		)
		(fp_line
			(start -0.67945 -0.3048)
			(end -0.67945 0.3048)
			(stroke
				(width 0.1)
				(type default)
			)
			(layer "B.Fab")
		)
		(fp_line
			(start -0.67945 0.3048)
			(end -0.120396 0.3048)
			(stroke
				(width 0.1)
				(type default)
			)
			(layer "B.Fab")
		)
		(fp_line
			(start -0.12065 -0.3048)
			(end -0.67945 -0.3048)
			(stroke
				(width 0.1)
				(type default)
			)
			(layer "B.Fab")
		)
		(fp_line
			(start -0.12065 -0.2794)
			(end -0.12065 -0.3048)
			(stroke
				(width 0.1)
				(type default)
			)
			(layer "B.Fab")
		)
		(fp_line
			(start -0.120396 0.2794)
			(end 0.12065 0.2794)
			(stroke
				(width 0.1)
				(type default)
			)
			(layer "B.Fab")
		)
		(fp_line
			(start -0.120396 0.3048)
			(end -0.120396 0.2794)
			(stroke
				(width 0.1)
				(type default)
			)
			(layer "B.Fab")
		)
		(fp_line
			(start 0.12065 -0.305054)
			(end 0.12065 -0.2794)
			(stroke
				(width 0.1)
				(type default)
			)
			(layer "B.Fab")
		)
		(fp_line
			(start 0.12065 -0.2794)
			(end -0.12065 -0.2794)
			(stroke
				(width 0.1)
				(type default)
			)
			(layer "B.Fab")
		)
		(fp_line
			(start 0.12065 0.2794)
			(end 0.12065 0.3048)
			(stroke
				(width 0.1)
				(type default)
			)
			(layer "B.Fab")
		)
		(fp_line
			(start 0.12065 0.3048)
			(end 0.67945 0.3048)
			(stroke
				(width 0.1)
				(type default)
			)
			(layer "B.Fab")
		)
		(fp_line
			(start 0.67945 -0.305054)
			(end 0.12065 -0.305054)
			(stroke
				(width 0.1)
				(type default)
			)
			(layer "B.Fab")
		)
		(fp_line
			(start 0.67945 0.3048)
			(end 0.67945 -0.305054)
			(stroke
				(width 0.1)
				(type default)
			)
			(layer "B.Fab")
		)
		(pad "1" smd circle
			(at 0.40005 0 180)
			(size 0 0)
			(layers "B.Cu" "B.Mask" "B.Paste")
			(net "P52V_HS1_1272_GATE")
		)
		(pad "2" smd circle
			(at -0.40005 0 180)
			(size 0 0)
			(layers "B.Cu" "B.Mask" "B.Paste")
			(net "P52V_HS1_GATE2_R")
		)
	)
	(footprint ""
		(layer "B.Cu")
		(at 224.282 -90.043 90)
		(property "Reference" "C10"
			(at 0 0 90)
			(layer "B.SilkS")
			(hide yes)
			(effects
				(font
					(size 1.27 1.27)
				)
				(justify mirror)
			)
		)
		(property "Value" ""
			(at 0 0 90)
			(layer "B.Fab")
			(effects
				(font
					(size 1.27 1.27)
				)
				(justify mirror)
			)
		)
		(duplicate_pad_numbers_are_jumpers no)
		(fp_line
			(start 0.7874 -0.4064)
			(end -0.7874 -0.4064)
			(stroke
				(width 0.1524)
				(type default)
			)
			(layer "B.SilkS")
		)
		(fp_line
			(start -0.7874 -0.4064)
			(end -0.7874 0.4064)
			(stroke
				(width 0.1524)
				(type default)
			)
			(layer "B.SilkS")
		)
		(fp_line
			(start 0.7874 0.4064)
			(end 0.7874 -0.4064)
			(stroke
				(width 0.1524)
				(type default)
			)
			(layer "B.SilkS")
		)
		(fp_line
			(start -0.7874 0.4064)
			(end 0.7874 0.4064)
			(stroke
				(width 0.1524)
				(type default)
			)
			(layer "B.SilkS")
		)
		(fp_line
			(start 0.67945 -0.305054)
			(end 0.12065 -0.305054)
			(stroke
				(width 0.1)
				(type default)
			)
			(layer "B.Fab")
		)
		(fp_line
			(start 0.12065 -0.305054)
			(end 0.12065 -0.2794)
			(stroke
				(width 0.1)
				(type default)
			)
			(layer "B.Fab")
		)
		(fp_line
			(start -0.12065 -0.3048)
			(end -0.67945 -0.3048)
			(stroke
				(width 0.1)
				(type default)
			)
			(layer "B.Fab")
		)
		(fp_line
			(start -0.67945 -0.3048)
			(end -0.67945 0.3048)
			(stroke
				(width 0.1)
				(type default)
			)
			(layer "B.Fab")
		)
		(fp_line
			(start 0.12065 -0.2794)
			(end -0.12065 -0.2794)
			(stroke
				(width 0.1)
				(type default)
			)
			(layer "B.Fab")
		)
		(fp_line
			(start -0.12065 -0.2794)
			(end -0.12065 -0.3048)
			(stroke
				(width 0.1)
				(type default)
			)
			(layer "B.Fab")
		)
		(fp_line
			(start 0.12065 0.2794)
			(end 0.12065 0.3048)
			(stroke
				(width 0.1)
				(type default)
			)
			(layer "B.Fab")
		)
		(fp_line
			(start -0.120396 0.2794)
			(end 0.12065 0.2794)
			(stroke
				(width 0.1)
				(type default)
			)
			(layer "B.Fab")
		)
		(fp_line
			(start 0.67945 0.3048)
			(end 0.67945 -0.305054)
			(stroke
				(width 0.1)
				(type default)
			)
			(layer "B.Fab")
		)
		(fp_line
			(start 0.12065 0.3048)
			(end 0.67945 0.3048)
			(stroke
				(width 0.1)
				(type default)
			)
			(layer "B.Fab")
		)
		(fp_line
			(start -0.120396 0.3048)
			(end -0.120396 0.2794)
			(stroke
				(width 0.1)
				(type default)
			)
			(layer "B.Fab")
		)
		(fp_line
			(start -0.67945 0.3048)
			(end -0.120396 0.3048)
			(stroke
				(width 0.1)
				(type default)
			)
			(layer "B.Fab")
		)
		(pad "1" smd circle
			(at 0.40005 0 270)
			(size 0 0)
			(layers "B.Cu" "B.Mask" "B.Paste")
			(net "GND")
		)
		(pad "2" smd circle
			(at -0.40005 0 270)
			(size 0 0)
			(layers "B.Cu" "B.Mask" "B.Paste")
			(net "P3V3_AUX")
		)
	)
	(footprint ""
		(layer "B.Cu")
		(at 289.306 -50.927)
		(property "Reference" "PC2"
			(at 0 0 0)
			(layer "B.SilkS")
			(hide yes)
			(effects
				(font
					(size 1.27 1.27)
				)
				(justify mirror)
			)
		)
		(property "Value" ""
			(at 0 0 0)
			(layer "B.Fab")
			(effects
				(font
					(size 1.27 1.27)
				)
				(justify mirror)
			)
		)
		(duplicate_pad_numbers_are_jumpers no)
		(fp_line
			(start -0.7874 -0.4064)
			(end -0.7874 0.4064)
			(stroke
				(width 0.1524)
				(type default)
			)
			(layer "B.SilkS")
		)
		(fp_line
			(start -0.7874 0.4064)
			(end 0.7874 0.4064)
			(stroke
				(width 0.1524)
				(type default)
			)
			(layer "B.SilkS")
		)
		(fp_line
			(start 0.7874 -0.4064)
			(end -0.7874 -0.4064)
			(stroke
				(width 0.1524)
				(type default)
			)
			(layer "B.SilkS")
		)
		(fp_line
			(start 0.7874 0.4064)
			(end 0.7874 -0.4064)
			(stroke
				(width 0.1524)
				(type default)
			)
			(layer "B.SilkS")
		)
		(fp_line
			(start -0.67945 -0.3048)
			(end -0.67945 0.3048)
			(stroke
				(width 0.1)
				(type default)
			)
			(layer "B.Fab")
		)
		(fp_line
			(start -0.67945 0.3048)
			(end -0.120396 0.3048)
			(stroke
				(width 0.1)
				(type default)
			)
			(layer "B.Fab")
		)
		(fp_line
			(start -0.12065 -0.3048)
			(end -0.67945 -0.3048)
			(stroke
				(width 0.1)
				(type default)
			)
			(layer "B.Fab")
		)
		(fp_line
			(start -0.12065 -0.2794)
			(end -0.12065 -0.3048)
			(stroke
				(width 0.1)
				(type default)
			)
			(layer "B.Fab")
		)
		(fp_line
			(start -0.120396 0.2794)
			(end 0.12065 0.2794)
			(stroke
				(width 0.1)
				(type default)
			)
			(layer "B.Fab")
		)
		(fp_line
			(start -0.120396 0.3048)
			(end -0.120396 0.2794)
			(stroke
				(width 0.1)
				(type default)
			)
			(layer "B.Fab")
		)
		(fp_line
			(start 0.12065 -0.305054)
			(end 0.12065 -0.2794)
			(stroke
				(width 0.1)
				(type default)
			)
			(layer "B.Fab")
		)
		(fp_line
			(start 0.12065 -0.2794)
			(end -0.12065 -0.2794)
			(stroke
				(width 0.1)
				(type default)
			)
			(layer "B.Fab")
		)
		(fp_line
			(start 0.12065 0.2794)
			(end 0.12065 0.3048)
			(stroke
				(width 0.1)
				(type default)
			)
			(layer "B.Fab")
		)
		(fp_line
			(start 0.12065 0.3048)
			(end 0.67945 0.3048)
			(stroke
				(width 0.1)
				(type default)
			)
			(layer "B.Fab")
		)
		(fp_line
			(start 0.67945 -0.305054)
			(end 0.12065 -0.305054)
			(stroke
				(width 0.1)
				(type default)
			)
			(layer "B.Fab")
		)
		(fp_line
			(start 0.67945 0.3048)
			(end 0.67945 -0.305054)
			(stroke
				(width 0.1)
				(type default)
			)
			(layer "B.Fab")
		)
		(pad "1" smd circle
			(at 0.40005 0 180)
			(size 0 0)
			(layers "B.Cu" "B.Mask" "B.Paste")
			(net "P52V_HS1_UVLO_EN")
		)
		(pad "2" smd circle
			(at -0.40005 0 180)
			(size 0 0)
			(layers "B.Cu" "B.Mask" "B.Paste")
			(net "GND_FIELD_SIGNAL")
		)
	)
)
